#ISCELL
  pure_quanta quanta_title_block_c *
  *
#ISCELL
  pure_quanta_power universal_gnd *
  page264_i16
#CELL
  pure_quanta q_res *
  page264_i17
#ISCELL
  standard offpage *
  page264_i18
#ISCELL
  standard offpage *
  page264_i2
#ISCELL
  pure_quanta_power universal_gnd *
  page264_i23
#CELL
  pure_quanta q_res *
  page264_i24
#CELL
  pure_quanta q_res *
  page264_i25
#CELL
  pure_quanta q_res *
  page264_i26
#CELL
  pure_quanta q_res *
  page264_i27
#ISCELL
  pure_quanta_power universal_gnd *
  page264_i28
#ISCELL
  pure_quanta_power universal_power *
  page264_i29
#ISCELL
  standard offpage *
  page264_i3
#CELL
  pure_quanta q_res *
  page264_i30
#ISCELL
  pure_quanta_power universal_power *
  page264_i31
#ISCELL
  pure_quanta_power universal_gnd *
  page264_i32
#CELL
  pure_quanta bss138dw7f *
  page264_i33
#ISCELL
  pure_quanta_power universal_gnd *
  page264_i34
#ISCELL
  pure_quanta_power universal_gnd *
  page264_i35
#CELL
  pure_quanta bss138dw7f *
  page264_i36
#ISCELL
  pure_quanta_power universal_gnd *
  page264_i37
#ISCELL
  pure_quanta_power universal_power *
  page264_i38
#CELL
  pure_quanta q_res *
  page264_i39
#ISCELL
  pure_quanta_power universal_power *
  page264_i40
#CELL
  pure_quanta q_res *
  page264_i41
#ISCELL
  pure_quanta_power p1v0_aux *
  page264_i42
#CELL
  pure_quanta q_res *
  page264_i43
#ISCELL
  standard offpage *
  page264_i44
#ISCELL
  pure_quanta_power p1v0_aux *
  page264_i45
#ISCELL
  standard offpage *
  page264_i46
#CELL
  pure_quanta q_cap *
  page264_i47
#ISCELL
  pure_quanta_power p1v0_aux *
  page264_i48
#CELL
  pure_quanta q_cap *
  page264_i49
#CELL
  pure_quanta q_res *
  page264_i5
#ISCELL
  pure_quanta_power universal_gnd *
  page264_i50
#CELL
  pure_quanta q_res *
  page264_i51
#ISCELL
  pure_quanta_power p1v0_aux *
  page264_i52
#ISCELL
  pure_quanta_power universal_power *
  page264_i53
#CELL
  pure_quanta q_res_4p_12 *
  page264_i54
#ISCELL
  pure_quanta_power universal_power *
  page264_i55
#ISCELL
  pure_quanta_power universal_power *
  page264_i56
#ISCELL
  pure_quanta_power universal_power *
  page264_i57
#CELL
  pure_quanta q_res_4p_12 *
  page264_i58
#CELL
  pure_quanta q_res *
  page264_i6
#ISCELL
  pure_quanta_power universal_gnd *
  page264_i7
#CELL
  pure_quanta sn74lvc1g11dckr *
  page264_i8
